# S9S_MB_2U (Grand Teton) — schematic netlist excerpt (pin names and nets, part order shuffled) for the footprints in the layout excerpt that follows; sources: Cadence DE-HDL packaged netlist, KiCad conversion of 03242023_DA0F0TMBIJ0_F0T_Motherboard_J_brd_V01_OCP.brd

C821  Q_CAP_DIFFBUS  DIFF BUS_0.22UF 6.3V 20% X6S  pkg C0201  page 175 : \1\ = P5E_CPU1_PE1_TX_C_DP<8> ; \2\ = P5E_CPU1_PE1_TX_DP<8>
C278  Q_CAP  22UF 4V 20% X6S  pkg C0402  page 77 : A = PVCCIN_CPU1 ; B = GND
R3831  Q_RES  0 5% EMPTY  pkg 0402LF  page 162 : A = P12V_OCP_PWRGD_2 ; B = HP_LVC3_OCP_V3_2_P12V_PWRGD

(kicad_pcb
	(version 20260206)
	(generator "pcbnew")
	(generator_version "10.0")
	(general
		(thickness 1.6)
		(legacy_teardrops no)
	)
	(paper "A4")
	(title_block
		(title "03242023_DA0F0TMBIJ0_F0T_Motherboard_J_brd_V01_OCP.brd")
		(comment 1 "Grand Teton / footprints 799-801 of 6105")
	)
	(layers
		(0 "F.Cu" signal "TOP")
		(4 "In1.Cu" signal "GND")
		(6 "In2.Cu" signal "IN1")
		(8 "In3.Cu" signal "GND1")
		(10 "In4.Cu" signal "IN2")
		(12 "In5.Cu" signal "GND2")
		(14 "In6.Cu" signal "IN3")
		(16 "In7.Cu" signal "GND3")
		(18 "In8.Cu" signal "VCC")
		(20 "In9.Cu" signal "VCC1")
		(22 "In10.Cu" signal "GND4")
		(24 "In11.Cu" signal "IN4")
		(26 "In12.Cu" signal "GND5")
		(28 "In13.Cu" signal "IN5")
		(30 "In14.Cu" signal "GND6")
		(32 "In15.Cu" signal "IN6")
		(34 "In16.Cu" signal "GND7")
		(2 "B.Cu" signal "BOTTOM")
		(9 "F.Adhes" user "F.Adhesive")
		(11 "B.Adhes" user "B.Adhesive")
		(13 "F.Paste" user "Package Geometry/Pastemask Top")
		(15 "B.Paste" user "Package Geometry/Pastemask Bottom")
		(5 "F.SilkS" user "Ref Des/Silkscreen Top")
		(7 "B.SilkS" user "Ref Des/Silkscreen Bottom")
		(1 "F.Mask" user "Board Geometry/Soldermask Top")
		(3 "B.Mask" user "Board Geometry/Soldermask Bottom")
		(17 "Dwgs.User" user "User.Drawings")
		(19 "Cmts.User" user "User.Comments")
		(21 "Eco1.User" user "User.Eco1")
		(23 "Eco2.User" user "User.Eco2")
		(25 "Edge.Cuts" user "Board Geometry/Outline")
		(27 "Margin" user)
		(31 "F.CrtYd" user "Package Geometry/Place Bound Top")
		(29 "B.CrtYd" user "Package Geometry/Place Bound Bottom")
		(35 "F.Fab" user "Ref Des/Assembly Top")
		(33 "B.Fab" user "Ref Des/Assembly Bottom")
	)
	(footprint ""
		(layer "F.Cu")
		(at 117.526816 -249.320558 -90)
		(property "Reference" "C278"
			(at 0 0 270)
			(layer "F.SilkS")
			(hide yes)
			(effects
				(font
					(size 1.27 1.27)
				)
			)
		)
		(property "Value" ""
			(at 0 0 270)
			(layer "F.Fab")
			(effects
				(font
					(size 1.27 1.27)
				)
			)
		)
		(duplicate_pad_numbers_are_jumpers no)
		(fp_line
			(start -0.7874 0.4064)
			(end -0.7874 -0.4064)
			(stroke
				(width 0.1524)
				(type default)
			)
			(layer "F.SilkS")
		)
		(fp_line
			(start 0.7874 0.4064)
			(end -0.7874 0.4064)
			(stroke
				(width 0.1524)
				(type default)
			)
			(layer "F.SilkS")
		)
		(fp_line
			(start -0.7874 -0.4064)
			(end 0.7874 -0.4064)
			(stroke
				(width 0.1524)
				(type default)
			)
			(layer "F.SilkS")
		)
		(fp_line
			(start 0.7874 -0.4064)
			(end 0.7874 0.4064)
			(stroke
				(width 0.1524)
				(type default)
			)
			(layer "F.SilkS")
		)
		(fp_line
			(start -0.67945 0.3048)
			(end -0.67945 -0.305054)
			(stroke
				(width 0.1)
				(type default)
			)
			(layer "F.Fab")
		)
		(fp_line
			(start -0.12065 0.3048)
			(end -0.67945 0.3048)
			(stroke
				(width 0.1)
				(type default)
			)
			(layer "F.Fab")
		)
		(fp_line
			(start 0.120396 0.3048)
			(end 0.120396 0.2794)
			(stroke
				(width 0.1)
				(type default)
			)
			(layer "F.Fab")
		)
		(fp_line
			(start 0.67945 0.3048)
			(end 0.120396 0.3048)
			(stroke
				(width 0.1)
				(type default)
			)
			(layer "F.Fab")
		)
		(fp_line
			(start -0.12065 0.2794)
			(end -0.12065 0.3048)
			(stroke
				(width 0.1)
				(type default)
			)
			(layer "F.Fab")
		)
		(fp_line
			(start 0.120396 0.2794)
			(end -0.12065 0.2794)
			(stroke
				(width 0.1)
				(type default)
			)
			(layer "F.Fab")
		)
		(fp_line
			(start -0.12065 -0.2794)
			(end 0.12065 -0.2794)
			(stroke
				(width 0.1)
				(type default)
			)
			(layer "F.Fab")
		)
		(fp_line
			(start 0.12065 -0.2794)
			(end 0.12065 -0.3048)
			(stroke
				(width 0.1)
				(type default)
			)
			(layer "F.Fab")
		)
		(fp_line
			(start 0.12065 -0.3048)
			(end 0.67945 -0.3048)
			(stroke
				(width 0.1)
				(type default)
			)
			(layer "F.Fab")
		)
		(fp_line
			(start 0.67945 -0.3048)
			(end 0.67945 0.3048)
			(stroke
				(width 0.1)
				(type default)
			)
			(layer "F.Fab")
		)
		(fp_line
			(start -0.67945 -0.305054)
			(end -0.12065 -0.305054)
			(stroke
				(width 0.1)
				(type default)
			)
			(layer "F.Fab")
		)
		(fp_line
			(start -0.12065 -0.305054)
			(end -0.12065 -0.2794)
			(stroke
				(width 0.1)
				(type default)
			)
			(layer "F.Fab")
		)
		(pad "1" smd circle
			(at -0.40005 0 270)
			(size 0 0)
			(layers "F.Cu" "F.Mask" "F.Paste")
			(net "PVCCIN_CPU1")
		)
		(pad "2" smd circle
			(at 0.40005 0 270)
			(size 0 0)
			(layers "F.Cu" "F.Mask" "F.Paste")
			(net "GND")
		)
	)
	(footprint ""
		(layer "F.Cu")
		(at 35.980878 -17.623536 90)
		(property "Reference" "C821"
			(at 0 0 90)
			(layer "F.SilkS")
			(hide yes)
			(effects
				(font
					(size 1.27 1.27)
				)
			)
		)
		(property "Value" ""
			(at 0 0 90)
			(layer "F.Fab")
			(effects
				(font
					(size 1.27 1.27)
				)
			)
		)
		(duplicate_pad_numbers_are_jumpers no)
		(fp_line
			(start 0.299974 -0.150114)
			(end 0.299974 0.150114)
			(stroke
				(width 0.1)
				(type default)
			)
			(layer "F.Fab")
		)
		(fp_line
			(start -0.299974 -0.150114)
			(end 0.299974 -0.150114)
			(stroke
				(width 0.1)
				(type default)
			)
			(layer "F.Fab")
		)
		(fp_line
			(start 0.299974 0.150114)
			(end -0.299974 0.150114)
			(stroke
				(width 0.1)
				(type default)
			)
			(layer "F.Fab")
		)
		(fp_line
			(start -0.299974 0.150114)
			(end -0.299974 -0.150114)
			(stroke
				(width 0.1)
				(type default)
			)
			(layer "F.Fab")
		)
		(pad "1" smd rect
			(at -0.2667 0 90)
			(size 0.3048 0.381)
			(layers "F.Cu" "F.Mask" "F.Paste")
			(net "P5E_CPU1_PE1_TX_C_DP<8>")
		)
		(pad "2" smd rect
			(at 0.2667 0 90)
			(size 0.3048 0.381)
			(layers "F.Cu" "F.Mask" "F.Paste")
			(net "P5E_CPU1_PE1_TX_DP<8>")
		)
	)
	(footprint ""
		(layer "F.Cu")
		(at 82.306668 -17.745202)
		(property "Reference" "R3831"
			(at 0 0 0)
			(layer "F.SilkS")
			(hide yes)
			(effects
				(font
					(size 1.27 1.27)
				)
			)
		)
		(property "Value" ""
			(at 0 0 0)
			(layer "F.Fab")
			(effects
				(font
					(size 1.27 1.27)
				)
			)
		)
		(duplicate_pad_numbers_are_jumpers no)
		(fp_line
			(start -0.7874 -0.4064)
			(end 0.7874 -0.4064)
			(stroke
				(width 0.1524)
				(type default)
			)
			(layer "F.SilkS")
		)
		(fp_line
			(start -0.7874 0.4064)
			(end -0.7874 -0.4064)
			(stroke
				(width 0.1524)
				(type default)
			)
			(layer "F.SilkS")
		)
		(fp_line
			(start 0.7874 -0.4064)
			(end 0.7874 0.4064)
			(stroke
				(width 0.1524)
				(type default)
			)
			(layer "F.SilkS")
		)
		(fp_line
			(start 0.7874 0.4064)
			(end -0.7874 0.4064)
			(stroke
				(width 0.1524)
				(type default)
			)
			(layer "F.SilkS")
		)
		(fp_line
			(start -0.67945 -0.305054)
			(end -0.12065 -0.305054)
			(stroke
				(width 0.1)
				(type default)
			)
			(layer "F.Fab")
		)
		(fp_line
			(start -0.67945 0.3048)
			(end -0.67945 -0.305054)
			(stroke
				(width 0.1)
				(type default)
			)
			(layer "F.Fab")
		)
		(fp_line
			(start -0.12065 -0.305054)
			(end -0.12065 -0.2794)
			(stroke
				(width 0.1)
				(type default)
			)
			(layer "F.Fab")
		)
		(fp_line
			(start -0.12065 -0.2794)
			(end 0.12065 -0.2794)
			(stroke
				(width 0.1)
				(type default)
			)
			(layer "F.Fab")
		)
		(fp_line
			(start -0.12065 0.2794)
			(end -0.12065 0.3048)
			(stroke
				(width 0.1)
				(type default)
			)
			(layer "F.Fab")
		)
		(fp_line
			(start -0.12065 0.3048)
			(end -0.67945 0.3048)
			(stroke
				(width 0.1)
				(type default)
			)
			(layer "F.Fab")
		)
		(fp_line
			(start 0.120396 0.2794)
			(end -0.12065 0.2794)
			(stroke
				(width 0.1)
				(type default)
			)
			(layer "F.Fab")
		)
		(fp_line
			(start 0.120396 0.3048)
			(end 0.120396 0.2794)
			(stroke
				(width 0.1)
				(type default)
			)
			(layer "F.Fab")
		)
		(fp_line
			(start 0.12065 -0.3048)
			(end 0.67945 -0.3048)
			(stroke
				(width 0.1)
				(type default)
			)
			(layer "F.Fab")
		)
		(fp_line
			(start 0.12065 -0.2794)
			(end 0.12065 -0.3048)
			(stroke
				(width 0.1)
				(type default)
			)
			(layer "F.Fab")
		)
		(fp_line
			(start 0.67945 -0.3048)
			(end 0.67945 0.3048)
			(stroke
				(width 0.1)
				(type default)
			)
			(layer "F.Fab")
		)
		(fp_line
			(start 0.67945 0.3048)
			(end 0.120396 0.3048)
			(stroke
				(width 0.1)
				(type default)
			)
			(layer "F.Fab")
		)
		(pad "1" smd circle
			(at -0.40005 0)
			(size 0 0)
			(layers "F.Cu" "F.Mask" "F.Paste")
			(net "P12V_OCP_PWRGD_2")
		)
		(pad "2" smd circle
			(at 0.40005 0)
			(size 0 0)
			(layers "F.Cu" "F.Mask" "F.Paste")
			(net "HP_LVC3_OCP_V3_2_P12V_PWRGD")
		)
	)
)
